# S9S_MB_2U (Grand Teton) — schematic netlist excerpt (pin names and nets, part order shuffled) for the footprints in the layout excerpt that follows; sources: Cadence DE-HDL packaged netlist, KiCad conversion of 03242023_DA0F0TMBIJ0_F0T_Motherboard_J_brd_V01_OCP.brd

PC1283  Q_CAP  0.22UF 25V 10% X7R  pkg C0402  page 300 : A = SW_PVNN_MAIN_CPU1_BST_R ; B = SW_PVNN_MAIN_CPU1_SW

(kicad_pcb
	(version 20260206)
	(generator "pcbnew")
	(generator_version "10.0")
	(general
		(thickness 1.6)
		(legacy_teardrops no)
	)
	(paper "A4")
	(title_block
		(title "03242023_DA0F0TMBIJ0_F0T_Motherboard_J_brd_V01_OCP.brd")
		(comment 1 "Grand Teton / footprints 3749-3749 of 6105")
	)
	(layers
		(0 "F.Cu" signal "TOP")
		(4 "In1.Cu" signal "GND")
		(6 "In2.Cu" signal "IN1")
		(8 "In3.Cu" signal "GND1")
		(10 "In4.Cu" signal "IN2")
		(12 "In5.Cu" signal "GND2")
		(14 "In6.Cu" signal "IN3")
		(16 "In7.Cu" signal "GND3")
		(18 "In8.Cu" signal "VCC")
		(20 "In9.Cu" signal "VCC1")
		(22 "In10.Cu" signal "GND4")
		(24 "In11.Cu" signal "IN4")
		(26 "In12.Cu" signal "GND5")
		(28 "In13.Cu" signal "IN5")
		(30 "In14.Cu" signal "GND6")
		(32 "In15.Cu" signal "IN6")
		(34 "In16.Cu" signal "GND7")
		(2 "B.Cu" signal "BOTTOM")
		(9 "F.Adhes" user "F.Adhesive")
		(11 "B.Adhes" user "B.Adhesive")
		(13 "F.Paste" user "Package Geometry/Pastemask Top")
		(15 "B.Paste" user "Package Geometry/Pastemask Bottom")
		(5 "F.SilkS" user "Ref Des/Silkscreen Top")
		(7 "B.SilkS" user "Ref Des/Silkscreen Bottom")
		(1 "F.Mask" user "Board Geometry/Soldermask Top")
		(3 "B.Mask" user "Board Geometry/Soldermask Bottom")
		(17 "Dwgs.User" user "User.Drawings")
		(19 "Cmts.User" user "User.Comments")
		(21 "Eco1.User" user "User.Eco1")
		(23 "Eco2.User" user "User.Eco2")
		(25 "Edge.Cuts" user "Board Geometry/Outline")
		(27 "Margin" user)
		(31 "F.CrtYd" user "Package Geometry/Place Bound Top")
		(29 "B.CrtYd" user "Package Geometry/Place Bound Bottom")
		(35 "F.Fab" user "Ref Des/Assembly Top")
		(33 "B.Fab" user "Ref Des/Assembly Bottom")
	)
	(footprint ""
		(layer "F.Cu")
		(at 25.632156 -180.529738 90)
		(property "Reference" "PC1283"
			(at 0 0 90)
			(layer "F.SilkS")
			(hide yes)
			(effects
				(font
					(size 1.27 1.27)
				)
			)
		)
		(property "Value" ""
			(at 0 0 90)
			(layer "F.Fab")
			(effects
				(font
					(size 1.27 1.27)
				)
			)
		)
		(duplicate_pad_numbers_are_jumpers no)
		(fp_line
			(start 0.7874 -0.4064)
			(end 0.7874 0.4064)
			(stroke
				(width 0.1524)
				(type default)
			)
			(layer "F.SilkS")
		)
		(fp_line
			(start -0.7874 -0.4064)
			(end 0.7874 -0.4064)
			(stroke
				(width 0.1524)
				(type default)
			)
			(layer "F.SilkS")
		)
		(fp_line
			(start 0.7874 0.4064)
			(end -0.7874 0.4064)
			(stroke
				(width 0.1524)
				(type default)
			)
			(layer "F.SilkS")
		)
		(fp_line
			(start -0.7874 0.4064)
			(end -0.7874 -0.4064)
			(stroke
				(width 0.1524)
				(type default)
			)
			(layer "F.SilkS")
		)
		(fp_line
			(start -0.12065 -0.305054)
			(end -0.12065 -0.2794)
			(stroke
				(width 0.1)
				(type default)
			)
			(layer "F.Fab")
		)
		(fp_line
			(start -0.67945 -0.305054)
			(end -0.12065 -0.305054)
			(stroke
				(width 0.1)
				(type default)
			)
			(layer "F.Fab")
		)
		(fp_line
			(start 0.67945 -0.3048)
			(end 0.67945 0.3048)
			(stroke
				(width 0.1)
				(type default)
			)
			(layer "F.Fab")
		)
		(fp_line
			(start 0.12065 -0.3048)
			(end 0.67945 -0.3048)
			(stroke
				(width 0.1)
				(type default)
			)
			(layer "F.Fab")
		)
		(fp_line
			(start 0.12065 -0.2794)
			(end 0.12065 -0.3048)
			(stroke
				(width 0.1)
				(type default)
			)
			(layer "F.Fab")
		)
		(fp_line
			(start -0.12065 -0.2794)
			(end 0.12065 -0.2794)
			(stroke
				(width 0.1)
				(type default)
			)
			(layer "F.Fab")
		)
		(fp_line
			(start 0.120396 0.2794)
			(end -0.12065 0.2794)
			(stroke
				(width 0.1)
				(type default)
			)
			(layer "F.Fab")
		)
		(fp_line
			(start -0.12065 0.2794)
			(end -0.12065 0.3048)
			(stroke
				(width 0.1)
				(type default)
			)
			(layer "F.Fab")
		)
		(fp_line
			(start 0.67945 0.3048)
			(end 0.120396 0.3048)
			(stroke
				(width 0.1)
				(type default)
			)
			(layer "F.Fab")
		)
		(fp_line
			(start 0.120396 0.3048)
			(end 0.120396 0.2794)
			(stroke
				(width 0.1)
				(type default)
			)
			(layer "F.Fab")
		)
		(fp_line
			(start -0.12065 0.3048)
			(end -0.67945 0.3048)
			(stroke
				(width 0.1)
				(type default)
			)
			(layer "F.Fab")
		)
		(fp_line
			(start -0.67945 0.3048)
			(end -0.67945 -0.305054)
			(stroke
				(width 0.1)
				(type default)
			)
			(layer "F.Fab")
		)
		(pad "1" smd circle
			(at -0.40005 0 90)
			(size 0 0)
			(layers "F.Cu" "F.Mask" "F.Paste")
			(net "SW_PVNN_MAIN_CPU1_BST_R")
		)
		(pad "2" smd circle
			(at 0.40005 0 90)
			(size 0 0)
			(layers "F.Cu" "F.Mask" "F.Paste")
			(net "SW_PVNN_MAIN_CPU1_SW")
		)
	)
)
